(kicad_pcb
	(version 20241229)
	(generator "pcbnew")
	(generator_version "9.0")
	(general
		(thickness 1.711)
		(legacy_teardrops no)
	)
	(paper "A4")
	(title_block
		(title "Antmicro Baseboard for Jetson AGX Thor")
		(date "2026-02-18")
		(rev "1.1.0")
		(company "Antmicro Ltd")
		(comment 1 "www.antmicro.com")
		(comment 9 "footprints 129-132 of 1170")
	)
	(layers
		(0 "F.Cu" signal)
		(4 "In1.Cu" signal)
		(6 "In2.Cu" signal)
		(8 "In3.Cu" signal)
		(10 "In4.Cu" jumper)
		(12 "In5.Cu" signal)
		(14 "In6.Cu" signal)
		(16 "In7.Cu" signal)
		(18 "In8.Cu" signal)
		(2 "B.Cu" signal)
		(9 "F.Adhes" user "F.Adhesive")
		(11 "B.Adhes" user "B.Adhesive")
		(13 "F.Paste" user)
		(15 "B.Paste" user)
		(5 "F.SilkS" user "F.Silkscreen")
		(7 "B.SilkS" user "B.Silkscreen")
		(1 "F.Mask" user)
		(3 "B.Mask" user)
		(17 "Dwgs.User" user "User.Drawings")
		(19 "Cmts.User" user "User.Comments")
		(21 "Eco1.User" user "User.Eco1")
		(23 "Eco2.User" user "User.Eco2")
		(25 "Edge.Cuts" user)
		(27 "Margin" user)
		(31 "F.CrtYd" user "F.Courtyard")
		(29 "B.CrtYd" user "B.Courtyard")
		(35 "F.Fab" user)
		(33 "B.Fab" user)
	)
	(footprint "antmicro-footprints:C_0402_1005Metric"
		(layer "F.Cu")
		(at 91.1 95.5)
		(descr "Capacitor SMD 0402")
		(tags "capacitor SMD 0402")
		(property "Reference" "C350"
			(at 1.1 0.500001 0)
			(layer "F.SilkS")
			(effects
				(font
					(size 0.7 0.7)
					(thickness 0.15)
				)
				(justify left bottom)
			)
		)
		(property "Value" "C_100n_0402"
			(at -1.022927 2.155213 0)
			(layer "F.Fab")
			(effects
				(font
					(size 0.7 0.7)
					(thickness 0.15)
				)
				(justify left bottom)
			)
		)
		(property "Datasheet" "https://www.murata.com/products/productdetail?partno=GRM155R61H104KE14%23"
			(at 0 0 0)
			(layer "F.Fab")
			(hide yes)
			(effects
				(font
					(size 1.27 1.27)
					(thickness 0.15)
				)
			)
		)
		(property "Description" "SMD Multilayer Ceramic Capacitor, 0.1 µF, 50 V, 0402 [1005 Metric], ± 10%, X5R, GRM Series"
			(at 0 0 0)
			(layer "F.Fab")
			(hide yes)
			(effects
				(font
					(size 1.27 1.27)
					(thickness 0.15)
				)
			)
		)
		(property "Manufacturer" "Murata"
			(at 0 0 0)
			(unlocked yes)
			(layer "F.Fab")
			(hide yes)
			(effects
				(font
					(size 1 1)
					(thickness 0.15)
				)
			)
		)
		(property "MPN" "GRM155R61H104KE14D"
			(at 0 0 0)
			(unlocked yes)
			(layer "F.Fab")
			(hide yes)
			(effects
				(font
					(size 1 1)
					(thickness 0.15)
				)
			)
		)
		(property "Val" "100n"
			(at 0 0 0)
			(unlocked yes)
			(layer "F.Fab")
			(hide yes)
			(effects
				(font
					(size 1 1)
					(thickness 0.15)
				)
			)
		)
		(property "License" "Apache-2.0"
			(at 0 0 0)
			(unlocked yes)
			(layer "F.Fab")
			(hide yes)
			(effects
				(font
					(size 1 1)
					(thickness 0.15)
				)
			)
		)
		(property "Author" "Antmicro"
			(at 0 0 0)
			(unlocked yes)
			(layer "F.Fab")
			(hide yes)
			(effects
				(font
					(size 1 1)
					(thickness 0.15)
				)
			)
		)
		(property "Voltage" "50V"
			(at 0 0 0)
			(unlocked yes)
			(layer "F.Fab")
			(hide yes)
			(effects
				(font
					(size 1 1)
					(thickness 0.15)
				)
			)
		)
		(property "Dielectric" "X5R"
			(at 0 0 0)
			(unlocked yes)
			(layer "F.Fab")
			(hide yes)
			(effects
				(font
					(size 1 1)
					(thickness 0.15)
				)
			)
		)
		(sheetname "/SoM_IO2/")
		(sheetfile "som_io2.kicad_sch")
		(attr smd)
		(fp_rect
			(start -0.925 -0.47)
			(end 0.925 0.47)
			(stroke
				(width 0.05)
				(type default)
			)
			(fill no)
			(layer "F.CrtYd")
		)
		(fp_line
			(start -0.494 -0.25)
			(end 0.504 -0.25)
			(stroke
				(width 0.15)
				(type solid)
			)
			(layer "F.Fab")
		)
		(fp_line
			(start -0.494 0.248)
			(end -0.494 -0.25)
			(stroke
				(width 0.15)
				(type solid)
			)
			(layer "F.Fab")
		)
		(fp_line
			(start 0.504 -0.25)
			(end 0.504 0.248)
			(stroke
				(width 0.15)
				(type solid)
			)
			(layer "F.Fab")
		)
		(fp_line
			(start 0.504 0.248)
			(end -0.494 0.248)
			(stroke
				(width 0.15)
				(type solid)
			)
			(layer "F.Fab")
		)
		(fp_text user "Author: Antmicro"
			(at -0.939 3.399 0)
			(layer "F.Fab")
			(effects
				(font
					(size 0.7 0.7)
					(thickness 0.15)
				)
				(justify left bottom)
			)
		)
		(fp_text user "${REFERENCE}"
			(at -0.939 4.599 0)
			(layer "F.Fab")
			(effects
				(font
					(size 0.7 0.7)
					(thickness 0.15)
				)
				(justify left bottom)
			)
		)
		(fp_text user "License: Apache-2.0"
			(at -0.939 5.799 0)
			(layer "F.Fab")
			(effects
				(font
					(size 0.7 0.7)
					(thickness 0.15)
				)
				(justify left bottom)
			)
		)
		(pad "1" smd roundrect
			(at -0.48 0)
			(size 0.59 0.64)
			(layers "F.Cu" "F.Mask" "F.Paste")
			(roundrect_rratio 0.25)
			(net 680 "/Expansion connector/DP3.TX2-")
			(pintype "passive")
		)
		(pad "2" smd roundrect
			(at 0.48 0)
			(size 0.59 0.64)
			(layers "F.Cu" "F.Mask" "F.Paste")
			(roundrect_rratio 0.25)
			(net 1270 "/SoM_IO2/DP3.TX2_C-")
			(pintype "passive")
		)
	)
	(footprint "antmicro-footprints:LED_0603_1608Metric_G"
		(layer "F.Cu")
		(at 166.25 55.3 -90)
		(descr "LED SMD 0603 Green")
		(tags "LED SMD 0603 Green")
		(property "Reference" "D31"
			(at -0.9 1.57 90)
			(layer "F.SilkS")
			(effects
				(font
					(size 0.7 0.7)
					(thickness 0.15)
				)
				(justify right top)
			)
		)
		(property "Value" "LED_G_0603_LTST-C190GKT"
			(at -0.001 1.599 90)
			(layer "F.Fab")
			(effects
				(font
					(size 0.7 0.7)
					(thickness 0.15)
				)
				(justify right top)
			)
		)
		(property "Datasheet" "https://media.digikey.com/pdf/Data%20Sheets/Lite-On%20PDFs/LTST-C190GKT.pdf"
			(at 0 0 90)
			(layer "F.Fab")
			(hide yes)
			(effects
				(font
					(size 1.27 1.27)
					(thickness 0.15)
				)
			)
		)
		(property "Description" "LED, Green, SMD, 0603, 20 mA, 2.1 V, 569 nm"
			(at 0 0 90)
			(layer "F.Fab")
			(hide yes)
			(effects
				(font
					(size 1.27 1.27)
					(thickness 0.15)
				)
			)
		)
		(property "MPN" "LTST-C190GKT"
			(at 0 0 270)
			(unlocked yes)
			(layer "F.Fab")
			(hide yes)
			(effects
				(font
					(size 1 1)
					(thickness 0.15)
				)
			)
		)
		(property "Manufacturer" "Lite-On"
			(at 0 0 270)
			(unlocked yes)
			(layer "F.Fab")
			(hide yes)
			(effects
				(font
					(size 1 1)
					(thickness 0.15)
				)
			)
		)
		(property "Author" "Antmicro"
			(at 0 0 270)
			(unlocked yes)
			(layer "F.Fab")
			(hide yes)
			(effects
				(font
					(size 1 1)
					(thickness 0.15)
				)
			)
		)
		(property "License" "Apache-2.0"
			(at 0 0 270)
			(unlocked yes)
			(layer "F.Fab")
			(hide yes)
			(effects
				(font
					(size 1 1)
					(thickness 0.15)
				)
			)
		)
		(property "Color" "Green"
			(at 0 0 270)
			(unlocked yes)
			(layer "F.Fab")
			(hide yes)
			(effects
				(font
					(size 1 1)
					(thickness 0.15)
				)
			)
		)
		(sheetname "/Power/")
		(sheetfile "power.kicad_sch")
		(attr smd)
		(fp_line
			(start 0.22 0.35)
			(end -0.22 0.35)
			(stroke
				(width 0.15)
				(type solid)
			)
			(layer "F.SilkS")
		)
		(fp_line
			(start -0.094672 0.201008)
			(end -0.094672 -0.198992)
			(stroke
				(width 0.1)
				(type solid)
			)
			(layer "F.SilkS")
		)
		(fp_line
			(start 0.105328 0.201008)
			(end -0.094672 0.001008)
			(stroke
				(width 0.1)
				(type solid)
			)
			(layer "F.SilkS")
		)
		(fp_line
			(start 0.105328 0.201008)
			(end 0.105328 -0.198992)
			(stroke
				(width 0.1)
				(type solid)
			)
			(layer "F.SilkS")
		)
		(fp_line
			(start -0.094672 0.001008)
			(end -0.24 0.001008)
			(stroke
				(width 0.1)
				(type solid)
			)
			(layer "F.SilkS")
		)
		(fp_line
			(start -0.094672 0.001008)
			(end 0.105328 -0.198992)
			(stroke
				(width 0.1)
				(type solid)
			)
			(layer "F.SilkS")
		)
		(fp_line
			(start 0.105328 0.001008)
			(end 0.24 0.001)
			(stroke
				(width 0.1)
				(type solid)
			)
			(layer "F.SilkS")
		)
		(fp_line
			(start -1.18 -0.319)
			(end -1.18 0.321)
			(stroke
				(width 0.15)
				(type solid)
			)
			(layer "F.SilkS")
		)
		(fp_line
			(start 0.22 -0.35)
			(end -0.22 -0.35)
			(stroke
				(width 0.15)
				(type solid)
			)
			(layer "F.SilkS")
		)
		(fp_rect
			(start 1.25 0.65)
			(end -1.25 -0.65)
			(stroke
				(width 0.05)
				(type solid)
			)
			(fill no)
			(layer "F.CrtYd")
		)
		(fp_line
			(start -0.199 0.2)
			(end -0.199 0.1)
			(stroke
				(width 0.15)
				(type solid)
			)
			(layer "F.Fab")
		)
		(fp_line
			(start 0.201 0.2)
			(end 0.201 0)
			(stroke
				(width 0.15)
				(type solid)
			)
			(layer "F.Fab")
		)
		(fp_line
			(start -0.199 0)
			(end -0.597 0)
			(stroke
				(width 0.15)
				(type solid)
			)
			(layer "F.Fab")
		)
		(fp_line
			(start -0.101 0)
			(end 0.201 0.2)
			(stroke
				(width 0.15)
				(type solid)
			)
			(layer "F.Fab")
		)
		(fp_line
			(start 0.201 0)
			(end 0.201 -0.202)
			(stroke
				(width 0.15)
				(type solid)
			)
			(layer "F.Fab")
		)
		(fp_line
			(start 0.599 0)
			(end 0.201 0)
			(stroke
				(width 0.15)
				(type solid)
			)
			(layer "F.Fab")
		)
		(fp_line
			(start -0.199 -0.202)
			(end -0.199 0.1)
			(stroke
				(width 0.15)
				(type solid)
			)
			(layer "F.Fab")
		)
		(fp_line
			(start 0.201 -0.202)
			(end -0.101 0)
			(stroke
				(width 0.15)
				(type solid)
			)
			(layer "F.Fab")
		)
		(fp_rect
			(start 0.848 0.4)
			(end -0.85 -0.402)
			(stroke
				(width 0.15)
				(type solid)
			)
			(fill no)
			(layer "F.Fab")
		)
		(fp_text user "${REFERENCE}"
			(at -1.4224 5.999 90)
			(layer "F.Fab")
			(effects
				(font
					(size 0.7 0.7)
					(thickness 0.15)
				)
				(justify right top)
			)
		)
		(fp_text user "License: Apache-2.0"
			(at -1.4224 3.599 90)
			(layer "F.Fab")
			(effects
				(font
					(size 0.7 0.7)
					(thickness 0.15)
				)
				(justify right top)
			)
		)
		(fp_text user "Author: Antmicro"
			(at -1.4224 4.799 90)
			(layer "F.Fab")
			(effects
				(font
					(size 0.7 0.7)
					(thickness 0.15)
				)
				(justify right top)
			)
		)
		(pad "1" smd roundrect
			(at -0.7 0 90)
			(size 0.8 1)
			(layers "F.Cu" "F.Mask" "F.Paste")
			(roundrect_rratio 0.2)
			(net 1 "GND")
			(pinfunction "C")
			(pintype "passive")
		)
		(pad "2" smd roundrect
			(at 0.7 0 90)
			(size 0.8 1)
			(layers "F.Cu" "F.Mask" "F.Paste")
			(roundrect_rratio 0.2)
			(net 639 "Net-(D31-A)")
			(pinfunction "A")
			(pintype "passive")
		)
	)
	(footprint "antmicro-footprints:C_0402_1005Metric"
		(layer "F.Cu")
		(at 105.869999 55.25 180)
		(descr "Capacitor SMD 0402")
		(tags "capacitor SMD 0402")
		(property "Reference" "C387"
			(at -0.930001 1.2 0)
			(layer "F.SilkS")
			(effects
				(font
					(size 0.7 0.7)
					(thickness 0.15)
				)
				(justify right top)
			)
		)
		(property "Value" "C_100n_0402"
			(at -1.022927 2.155213 0)
			(layer "F.Fab")
			(effects
				(font
					(size 0.7 0.7)
					(thickness 0.15)
				)
				(justify right top)
			)
		)
		(property "Datasheet" "https://www.murata.com/products/productdetail?partno=GRM155R61H104KE14%23"
			(at 0 0 0)
			(layer "F.Fab")
			(hide yes)
			(effects
				(font
					(size 1.27 1.27)
					(thickness 0.15)
				)
			)
		)
		(property "Description" "SMD Multilayer Ceramic Capacitor, 0.1 µF, 50 V, 0402 [1005 Metric], ± 10%, X5R, GRM Series"
			(at 0 0 0)
			(layer "F.Fab")
			(hide yes)
			(effects
				(font
					(size 1.27 1.27)
					(thickness 0.15)
				)
			)
		)
		(property "MPN" "GRM155R61H104KE14D"
			(at 0 0 180)
			(unlocked yes)
			(layer "F.Fab")
			(hide yes)
			(effects
				(font
					(size 1 1)
					(thickness 0.15)
				)
			)
		)
		(property "Manufacturer" "Murata"
			(at 0 0 180)
			(unlocked yes)
			(layer "F.Fab")
			(hide yes)
			(effects
				(font
					(size 1 1)
					(thickness 0.15)
				)
			)
		)
		(property "License" "Apache-2.0"
			(at 0 0 180)
			(unlocked yes)
			(layer "F.Fab")
			(hide yes)
			(effects
				(font
					(size 1 1)
					(thickness 0.15)
				)
			)
		)
		(property "Author" "Antmicro"
			(at 0 0 180)
			(unlocked yes)
			(layer "F.Fab")
			(hide yes)
			(effects
				(font
					(size 1 1)
					(thickness 0.15)
				)
			)
		)
		(property "Val" "100n"
			(at 0 0 180)
			(unlocked yes)
			(layer "F.Fab")
			(hide yes)
			(effects
				(font
					(size 1 1)
					(thickness 0.15)
				)
			)
		)
		(property "Voltage" "50V"
			(at 0 0 180)
			(unlocked yes)
			(layer "F.Fab")
			(hide yes)
			(effects
				(font
					(size 1 1)
					(thickness 0.15)
				)
			)
		)
		(property "Dielectric" "X5R"
			(at 0 0 180)
			(unlocked yes)
			(layer "F.Fab")
			(hide yes)
			(effects
				(font
					(size 1 1)
					(thickness 0.15)
				)
			)
		)
		(property "Public" "False"
			(at 0 0 180)
			(unlocked yes)
			(layer "F.Fab")
			(hide yes)
			(effects
				(font
					(size 1 1)
					(thickness 0.15)
				)
			)
		)
		(sheetname "/DCDC/")
		(sheetfile "dcdc.kicad_sch")
		(attr smd)
		(fp_poly
			(pts
				(xy -0.925 -0.47) (xy 0.925 -0.47) (xy 0.925 0.47) (xy -0.925 0.47)
			)
			(stroke
				(width 0.05)
				(type default)
			)
			(fill no)
			(layer "F.CrtYd")
		)
		(fp_line
			(start 0.504 0.248)
			(end -0.494 0.248)
			(stroke
				(width 0.15)
				(type solid)
			)
			(layer "F.Fab")
		)
		(fp_line
			(start 0.504 -0.25)
			(end 0.504 0.248)
			(stroke
				(width 0.15)
				(type solid)
			)
			(layer "F.Fab")
		)
		(fp_line
			(start -0.494 0.248)
			(end -0.494 -0.25)
			(stroke
				(width 0.15)
				(type solid)
			)
			(layer "F.Fab")
		)
		(fp_line
			(start -0.494 -0.25)
			(end 0.504 -0.25)
			(stroke
				(width 0.15)
				(type solid)
			)
			(layer "F.Fab")
		)
		(fp_text user "Author: Antmicro"
			(at -0.939 3.399 0)
			(layer "F.Fab")
			(effects
				(font
					(size 0.7 0.7)
					(thickness 0.15)
				)
				(justify right top)
			)
		)
		(fp_text user "License: Apache-2.0"
			(at -0.939 5.799 0)
			(layer "F.Fab")
			(effects
				(font
					(size 0.7 0.7)
					(thickness 0.15)
				)
				(justify right top)
			)
		)
		(fp_text user "${REFERENCE}"
			(at -0.939 4.599 0)
			(layer "F.Fab")
			(effects
				(font
					(size 0.7 0.7)
					(thickness 0.15)
				)
				(justify right top)
			)
		)
		(pad "1" smd roundrect
			(at -0.48 0 180)
			(size 0.59 0.64)
			(layers "F.Cu" "F.Mask" "F.Paste")
			(roundrect_rratio 0.25)
			(net 1 "GND")
			(pintype "passive")
		)
		(pad "2" smd roundrect
			(at 0.48 0 180)
			(size 0.59 0.64)
			(layers "F.Cu" "F.Mask" "F.Paste")
			(roundrect_rratio 0.25)
			(net 4 "+3V3_AON")
			(pintype "passive")
		)
	)
	(footprint "antmicro-footprints:R_0805_2012Metric"
		(layer "F.Cu")
		(at 162.829468 76.21 180)
		(property "Reference" "R284"
			(at 2.029468 0.71 0)
			(layer "F.SilkS")
			(effects
				(font
					(size 0.7 0.7)
					(thickness 0.15)
				)
				(justify right top)
			)
		)
		(property "Value" "R_0R001_0805"
			(at 0 1.8 0)
			(layer "F.Fab")
			(effects
				(font
					(size 0.7 0.7)
					(thickness 0.15)
				)
				(justify right top)
			)
		)
		(property "Datasheet" "https://www.eaton.com/content/dam/eaton/products/electronic-components/resources/data-sheet/eaton-msma-automotive-smd-current-sense-resistor-metal-strip-data-sheet-elx1179.pdf"
			(at 0 0 0)
			(layer "F.Fab")
			(hide yes)
			(effects
				(font
					(size 1.27 1.27)
					(thickness 0.15)
				)
			)
		)
		(property "Description" "Current Sense Resistors - SMD MSMA, 0805 SIZE, 1/2 Watt, 1 mohm, 50 TCR MnCu Metal AEC-Q"
			(at 0 0 0)
			(layer "F.Fab")
			(hide yes)
			(effects
				(font
					(size 1.27 1.27)
					(thickness 0.15)
				)
			)
		)
		(property "MPN" "MSMA0805R0010FSM"
			(at 0 0 180)
			(unlocked yes)
			(layer "F.Fab")
			(hide yes)
			(effects
				(font
					(size 1 1)
					(thickness 0.15)
				)
			)
		)
		(property "Manufacturer" "Eaton"
			(at 0 0 180)
			(unlocked yes)
			(layer "F.Fab")
			(hide yes)
			(effects
				(font
					(size 1 1)
					(thickness 0.15)
				)
			)
		)
		(property "License" "Apache-2.0"
			(at 0 0 180)
			(unlocked yes)
			(layer "F.Fab")
			(hide yes)
			(effects
				(font
					(size 1 1)
					(thickness 0.15)
				)
			)
		)
		(property "Author" "Antmicro"
			(at 0 0 180)
			(unlocked yes)
			(layer "F.Fab")
			(hide yes)
			(effects
				(font
					(size 1 1)
					(thickness 0.15)
				)
			)
		)
		(property "Val" "0R001"
			(at 0 0 180)
			(unlocked yes)
			(layer "F.Fab")
			(hide yes)
			(effects
				(font
					(size 1 1)
					(thickness 0.15)
				)
			)
		)
		(property "Tolerance" "1%"
			(at 0 0 180)
			(unlocked yes)
			(layer "F.Fab")
			(hide yes)
			(effects
				(font
					(size 1 1)
					(thickness 0.15)
				)
			)
		)
		(property "Public" "False"
			(at 0 0 180)
			(unlocked yes)
			(layer "F.Fab")
			(hide yes)
			(effects
				(font
					(size 1 1)
					(thickness 0.15)
				)
			)
		)
		(component_classes
			(class "DCDC_20V")
		)
		(sheetname "/DCDC/")
		(sheetfile "dcdc.kicad_sch")
		(attr smd)
		(fp_line
			(start -0.3 -0.701)
			(end 0.298 -0.701)
			(stroke
				(width 0.15)
				(type solid)
			)
			(layer "F.SilkS")
		)
		(fp_line
			(start -0.32 0.699)
			(end 0.28 0.699)
			(stroke
				(width 0.15)
				(type solid)
			)
			(layer "F.SilkS")
		)
		(fp_rect
			(start 1.95 -0.9)
			(end -1.95 0.9)
			(stroke
				(width 0.05)
				(type default)
			)
			(fill no)
			(layer "F.CrtYd")
		)
		(fp_line
			(start 0.949 -0.677)
			(end 0.949 0.675)
			(stroke
				(width 0.15)
				(type solid)
			)
			(layer "F.Fab")
		)
		(fp_line
			(start -0.951 0.68)
			(end 0.949 0.68)
			(stroke
				(width 0.15)
				(type solid)
			)
			(layer "F.Fab")
		)
		(fp_line
			(start -0.951 -0.677)
			(end -0.951 0.675)
			(stroke
				(width 0.15)
				(type solid)
			)
			(layer "F.Fab")
		)
		(fp_line
			(start -0.951 -0.682)
			(end 0.949 -0.682)
			(stroke
				(width 0.15)
				(type solid)
			)
			(layer "F.Fab")
		)
		(fp_text user "License: Apache-2.0"
			(at -1.9 5.75 0)
			(layer "F.Fab")
			(effects
				(font
					(size 0.7 0.7)
					(thickness 0.15)
				)
				(justify right top)
			)
		)
		(fp_text user "Author: Antmicro"
			(at -1.9 4.4 0)
			(layer "F.Fab")
			(effects
				(font
					(size 0.7 0.7)
					(thickness 0.15)
				)
				(justify right top)
			)
		)
		(fp_text user "${REFERENCE}"
			(at -1.9 3.1 0)
			(layer "F.Fab")
			(effects
				(font
					(size 0.7 0.7)
					(thickness 0.15)
				)
				(justify right top)
			)
		)
		(pad "1" smd roundrect
			(at -1.1 0 180)
			(size 1.2 1.3)
			(layers "F.Cu" "F.Mask" "F.Paste")
			(roundrect_rratio 0.25)
			(net 1105 "/DCDC/20V_OUT")
			(pintype "passive")
		)
		(pad "2" smd roundrect
			(at 1.1 0 180)
			(size 1.2 1.3)
			(layers "F.Cu" "F.Mask" "F.Paste")
			(roundrect_rratio 0.25)
			(net 904 "+20V")
			(pintype "passive")
		)
	)
)
